(kicad_pcb
	(version 20260206)
	(generator "pcbnew")
	(generator_version "10.0")
	(general
		(thickness 1.6)
		(legacy_teardrops no)
	)
	(paper "A4")
	(title_block
		(title "Wiwynn_Tioga_Pass_MB.brd")
		(comment 1 "Tioga Pass / footprints 2446-2452 of 4770")
	)
	(layers
		(0 "F.Cu" signal "TOP")
		(4 "In1.Cu" signal "L2GND")
		(6 "In2.Cu" signal "L3")
		(8 "In3.Cu" signal "L4GND")
		(10 "In4.Cu" signal "L5")
		(12 "In5.Cu" signal "L6GND")
		(14 "In6.Cu" signal "L7VCC")
		(16 "In7.Cu" signal "L8VCC")
		(18 "In8.Cu" signal "L9GND")
		(20 "In9.Cu" signal "L10")
		(22 "In10.Cu" signal "L11GND")
		(24 "In11.Cu" signal "L12")
		(26 "In12.Cu" signal "L13GND")
		(2 "B.Cu" signal "BOTTOM")
		(9 "F.Adhes" user "F.Adhesive")
		(11 "B.Adhes" user "B.Adhesive")
		(13 "F.Paste" user "Package Geometry/Pastemask Top")
		(15 "B.Paste" user "Package Geometry/Pastemask Bottom")
		(5 "F.SilkS" user "Ref Des/Silkscreen Top")
		(7 "B.SilkS" user "Ref Des/Silkscreen Bottom")
		(1 "F.Mask" user "Board Geometry/Soldermask Top")
		(3 "B.Mask" user "Board Geometry/Soldermask Bottom")
		(17 "Dwgs.User" user "User.Drawings")
		(19 "Cmts.User" user "User.Comments")
		(21 "Eco1.User" user "User.Eco1")
		(23 "Eco2.User" user "User.Eco2")
		(25 "Edge.Cuts" user "Board Geometry/Outline")
		(27 "Margin" user)
		(31 "F.CrtYd" user "Package Geometry/Place Bound Top")
		(29 "B.CrtYd" user "Package Geometry/Place Bound Bottom")
		(35 "F.Fab" user "Ref Des/Assembly Top")
		(33 "B.Fab" user "Ref Des/Assembly Bottom")
	)
	(footprint ""
		(layer "B.Cu")
		(at 421.812466 -44.647612 -90)
		(property "Reference" "R25W82"
			(at 0.8382 -0.67818 270)
			(unlocked yes)
			(layer "B.SilkS")
			(effects
				(font
					(size 0.4064 0.254)
					(thickness 0.1524)
				)
				(justify left mirror)
			)
		)
		(property "Value" ""
			(at 0 0 90)
			(layer "B.Fab")
			(effects
				(font
					(size 1.27 1.27)
				)
				(justify mirror)
			)
		)
		(duplicate_pad_numbers_are_jumpers no)
		(fp_poly
			(pts
				(xy 0.2794 -0.1016) (xy -0.2794 -0.1016) (xy -0.2794 0.9906) (xy 0.2794 0.9906)
			)
			(stroke
				(width 0)
				(type default)
			)
			(fill no)
			(layer "B.CrtYd")
		)
		(fp_line
			(start -0.2794 0.9906)
			(end -0.2794 -0.1016)
			(stroke
				(width 0.1)
				(type default)
			)
			(layer "B.Fab")
		)
		(fp_line
			(start 0.2794 0.9906)
			(end -0.2794 0.9906)
			(stroke
				(width 0.1)
				(type default)
			)
			(layer "B.Fab")
		)
		(fp_line
			(start -0.2794 -0.1016)
			(end 0.2794 -0.1016)
			(stroke
				(width 0.1)
				(type default)
			)
			(layer "B.Fab")
		)
		(fp_line
			(start 0.2794 -0.1016)
			(end 0.2794 0.9906)
			(stroke
				(width 0.1)
				(type default)
			)
			(layer "B.Fab")
		)
		(pad "1" smd rect
			(at 0 0 90)
			(size 0.508 0.508)
			(layers "B.Cu" "B.Mask" "B.Paste")
			(net "SPI_BMC_BT_DO")
		)
		(pad "2" smd rect
			(at 0 0.889 90)
			(size 0.508 0.508)
			(layers "B.Cu" "B.Mask" "B.Paste")
			(net "SPI_BMC_BT_DO_R")
		)
		(zone
			(layer "B.Cu")
			(hatch none 0.5)
			(connect_pads
				(clearance 0)
			)
			(min_thickness 0.25)
			(keepout
				(tracks not_allowed)
				(vias allowed)
				(pads allowed)
				(copperpour not_allowed)
				(footprints allowed)
			)
			(placement
				(enabled no)
				(sheetname "")
			)
			(fill
				(thermal_gap 0.5)
				(thermal_bridge_width 0.5)
				(island_removal_mode 0)
			)
			(polygon
				(pts
					(xy 421.177466 -44.393612) (xy 421.177466 -44.901612) (xy 421.558466 -44.901612) (xy 421.558466 -44.393612)
				)
			)
		)
		(zone
			(layer "B.Cu")
			(hatch none 0.5)
			(connect_pads
				(clearance 0)
			)
			(min_thickness 0.25)
			(keepout
				(tracks allowed)
				(vias not_allowed)
				(pads allowed)
				(copperpour not_allowed)
				(footprints allowed)
			)
			(placement
				(enabled no)
				(sheetname "")
			)
			(fill
				(thermal_gap 0.5)
				(thermal_bridge_width 0.5)
				(island_removal_mode 0)
			)
			(polygon
				(pts
					(xy 421.558466 -44.393612) (xy 421.558466 -44.901612) (xy 421.177466 -44.901612) (xy 421.177466 -44.393612)
				)
			)
		)
	)
	(footprint ""
		(layer "B.Cu")
		(at 169.037 -3.4544 90)
		(property "Reference" "C6U14"
			(at 0 0 90)
			(layer "B.SilkS")
			(hide yes)
			(effects
				(font
					(size 1.27 1.27)
				)
				(justify mirror)
			)
		)
		(property "Value" ""
			(at 0 0 90)
			(layer "B.Fab")
			(effects
				(font
					(size 1.27 1.27)
				)
				(justify mirror)
			)
		)
		(duplicate_pad_numbers_are_jumpers no)
		(fp_rect
			(start -0.4953 1.6002)
			(end 0.4953 -0.2032)
			(stroke
				(width 0)
				(type default)
			)
			(fill no)
			(layer "B.CrtYd")
		)
		(fp_line
			(start 0.4953 -0.2032)
			(end -0.4953 -0.2032)
			(stroke
				(width 0.1)
				(type default)
			)
			(layer "B.Fab")
		)
		(fp_line
			(start -0.4953 -0.2032)
			(end -0.4953 1.6002)
			(stroke
				(width 0.1)
				(type default)
			)
			(layer "B.Fab")
		)
		(fp_line
			(start 0.4953 1.6002)
			(end 0.4953 -0.2032)
			(stroke
				(width 0.1)
				(type default)
			)
			(layer "B.Fab")
		)
		(fp_line
			(start -0.4953 1.6002)
			(end 0.4953 1.6002)
			(stroke
				(width 0.1)
				(type default)
			)
			(layer "B.Fab")
		)
		(pad "1" smd rect
			(at 0 0 270)
			(size 0.762 0.889)
			(layers "B.Cu" "B.Mask" "B.Paste")
			(net "PVDDQ_GHJ")
		)
		(pad "2" smd rect
			(at 0 1.397 270)
			(size 0.762 0.889)
			(layers "B.Cu" "B.Mask" "B.Paste")
			(net "GND")
		)
		(zone
			(layer "B.Cu")
			(hatch none 0.5)
			(connect_pads
				(clearance 0)
			)
			(min_thickness 0.25)
			(keepout
				(tracks not_allowed)
				(vias allowed)
				(pads allowed)
				(copperpour not_allowed)
				(footprints allowed)
			)
			(placement
				(enabled no)
				(sheetname "")
			)
			(fill
				(thermal_gap 0.5)
				(thermal_bridge_width 0.5)
				(island_removal_mode 0)
			)
			(polygon
				(pts
					(xy 169.9895 -3.0734) (xy 169.9895 -3.8354) (xy 169.4815 -3.8354) (xy 169.4815 -3.0734)
				)
			)
		)
	)
	(footprint ""
		(layer "B.Cu")
		(at 273.433286 -68.17614 180)
		(property "Reference" "C5P41"
			(at 0 0 0)
			(layer "B.SilkS")
			(hide yes)
			(effects
				(font
					(size 1.27 1.27)
				)
				(justify mirror)
			)
		)
		(property "Value" ""
			(at 0 0 0)
			(layer "B.Fab")
			(effects
				(font
					(size 1.27 1.27)
				)
				(justify mirror)
			)
		)
		(duplicate_pad_numbers_are_jumpers no)
		(fp_poly
			(pts
				(xy 0.7239 -0.2159) (xy -0.7239 -0.2159) (xy -0.7239 1.9939) (xy 0.7239 1.9939)
			)
			(stroke
				(width 0)
				(type default)
			)
			(fill no)
			(layer "B.CrtYd")
		)
		(fp_line
			(start 0.7239 1.9939)
			(end -0.7239 1.9939)
			(stroke
				(width 0.1)
				(type default)
			)
			(layer "B.Fab")
		)
		(fp_line
			(start 0.7239 -0.2159)
			(end 0.7239 1.9939)
			(stroke
				(width 0.1)
				(type default)
			)
			(layer "B.Fab")
		)
		(fp_line
			(start -0.7239 1.9939)
			(end -0.7239 -0.2159)
			(stroke
				(width 0.1)
				(type default)
			)
			(layer "B.Fab")
		)
		(fp_line
			(start -0.7239 -0.2159)
			(end 0.7239 -0.2159)
			(stroke
				(width 0.1)
				(type default)
			)
			(layer "B.Fab")
		)
		(pad "1" smd rect
			(at 0 0)
			(size 1.27 1.016)
			(layers "B.Cu" "B.Mask" "B.Paste")
			(net "PVDDQ_ABC")
		)
		(pad "2" smd rect
			(at 0 1.778)
			(size 1.27 1.016)
			(layers "B.Cu" "B.Mask" "B.Paste")
			(net "GND")
		)
		(zone
			(layer "B.Cu")
			(hatch none 0.5)
			(connect_pads
				(clearance 0)
			)
			(min_thickness 0.25)
			(keepout
				(tracks not_allowed)
				(vias allowed)
				(pads allowed)
				(copperpour not_allowed)
				(footprints allowed)
			)
			(placement
				(enabled no)
				(sheetname "")
			)
			(fill
				(thermal_gap 0.5)
				(thermal_bridge_width 0.5)
				(island_removal_mode 0)
			)
			(polygon
				(pts
					(xy 272.798286 -68.68414) (xy 274.068286 -68.68414) (xy 274.068286 -69.44614) (xy 272.798286 -69.44614)
				)
			)
		)
	)
	(footprint ""
		(layer "B.Cu")
		(at 101.3968 -17.7546 90)
		(property "Reference" "C8T6"
			(at -1.848866 0.752348 90)
			(unlocked yes)
			(layer "B.SilkS")
			(effects
				(font
					(size 1.27 0.9652)
					(thickness 0.1524)
				)
				(justify mirror)
			)
		)
		(property "Value" ""
			(at 0 0 90)
			(layer "B.Fab")
			(effects
				(font
					(size 1.27 1.27)
				)
				(justify mirror)
			)
		)
		(duplicate_pad_numbers_are_jumpers no)
		(fp_rect
			(start 0.500126 1.598422)
			(end -0.500126 -0.201422)
			(stroke
				(width 0)
				(type default)
			)
			(fill no)
			(layer "B.CrtYd")
		)
		(fp_line
			(start 0.500126 -0.201422)
			(end -0.500126 -0.201422)
			(stroke
				(width 0.1)
				(type default)
			)
			(layer "B.Fab")
		)
		(fp_line
			(start -0.500126 -0.201422)
			(end -0.500126 1.598422)
			(stroke
				(width 0.1)
				(type default)
			)
			(layer "B.Fab")
		)
		(fp_line
			(start 0.500126 1.598422)
			(end 0.500126 -0.201422)
			(stroke
				(width 0.1)
				(type default)
			)
			(layer "B.Fab")
		)
		(fp_line
			(start -0.500126 1.598422)
			(end 0.500126 1.598422)
			(stroke
				(width 0.1)
				(type default)
			)
			(layer "B.Fab")
		)
		(pad "1" smd rect
			(at 0 0)
			(size 0.889 0.9906)
			(layers "B.Cu" "B.Mask" "B.Paste")
			(net "PVDDQ_GHJ")
		)
		(pad "2" smd rect
			(at 0 1.397)
			(size 0.889 0.9906)
			(layers "B.Cu" "B.Mask" "B.Paste")
			(net "GND")
		)
		(zone
			(layer "B.Cu")
			(hatch none 0.5)
			(connect_pads
				(clearance 0)
			)
			(min_thickness 0.25)
			(keepout
				(tracks not_allowed)
				(vias allowed)
				(pads allowed)
				(copperpour not_allowed)
				(footprints allowed)
			)
			(placement
				(enabled no)
				(sheetname "")
			)
			(fill
				(thermal_gap 0.5)
				(thermal_bridge_width 0.5)
				(island_removal_mode 0)
			)
			(polygon
				(pts
					(xy 102.3493 -18.2499) (xy 101.8413 -18.2499) (xy 101.8413 -17.2593) (xy 102.3493 -17.2593)
				)
			)
		)
		(zone
			(layer "B.Cu")
			(hatch none 0.5)
			(connect_pads
				(clearance 0)
			)
			(min_thickness 0.25)
			(keepout
				(tracks allowed)
				(vias not_allowed)
				(pads allowed)
				(copperpour not_allowed)
				(footprints allowed)
			)
			(placement
				(enabled no)
				(sheetname "")
			)
			(fill
				(thermal_gap 0.5)
				(thermal_bridge_width 0.5)
				(island_removal_mode 0)
			)
			(polygon
				(pts
					(xy 102.3493 -18.2499) (xy 101.8413 -18.2499) (xy 101.8413 -17.2593) (xy 102.3493 -17.2593)
				)
			)
		)
	)
	(footprint ""
		(layer "B.Cu")
		(at 484.124 -143.4084 90)
		(property "Reference" "CR1L4"
			(at 0 0 90)
			(layer "B.SilkS")
			(hide yes)
			(effects
				(font
					(size 1.27 1.27)
				)
				(justify mirror)
			)
		)
		(property "Value" ""
			(at 0 0 90)
			(layer "B.Fab")
			(effects
				(font
					(size 1.27 1.27)
				)
				(justify mirror)
			)
		)
		(duplicate_pad_numbers_are_jumpers no)
		(fp_line
			(start 0.9144 0.1016)
			(end 0.9144 2.9464)
			(stroke
				(width 0.1524)
				(type default)
			)
			(layer "B.SilkS")
		)
		(fp_line
			(start 0.8382 0.1016)
			(end 0.9144 0.1016)
			(stroke
				(width 0.1524)
				(type default)
			)
			(layer "B.SilkS")
		)
		(fp_line
			(start -0.8382 0.1016)
			(end -0.9144 0.1016)
			(stroke
				(width 0.1524)
				(type default)
			)
			(layer "B.SilkS")
		)
		(fp_line
			(start -0.9144 0.1016)
			(end -0.9144 2.9464)
			(stroke
				(width 0.1524)
				(type default)
			)
			(layer "B.SilkS")
		)
		(fp_line
			(start 0.9144 2.9464)
			(end 0.8382 2.9464)
			(stroke
				(width 0.1524)
				(type default)
			)
			(layer "B.SilkS")
		)
		(fp_line
			(start -0.9144 2.9464)
			(end -0.8382 2.9464)
			(stroke
				(width 0.1524)
				(type default)
			)
			(layer "B.SilkS")
		)
		(fp_circle
			(center -1.128776 -0.907288)
			(end -1.128776 -0.780288)
			(stroke
				(width 0.254)
				(type default)
			)
			(fill no)
			(layer "B.SilkS")
		)
		(fp_poly
			(pts
				(xy 0 0.1016) (xy -0.5334 0.1016) (xy -0.7366 0.1016) (xy -0.9144 0.1016) (xy -0.9144 2.9464) (xy -0.8382 2.9464)
				(xy -0.762 2.9464) (xy 0.9144 2.9464) (xy 0.9144 2.7686) (xy 0.9144 2.159) (xy 0.9144 0.1016) (xy 0.7366 0.1016)
				(xy 0.5842 0.1016)
			)
			(stroke
				(width 0)
				(type default)
			)
			(fill no)
			(layer "B.CrtYd")
		)
		(fp_line
			(start 0.9144 0.1016)
			(end 0.9144 2.9464)
			(stroke
				(width 0.1)
				(type default)
			)
			(layer "B.Fab")
		)
		(fp_line
			(start -0.9144 0.1016)
			(end 0.9144 0.1016)
			(stroke
				(width 0.1)
				(type default)
			)
			(layer "B.Fab")
		)
		(fp_line
			(start 0.9144 2.9464)
			(end -0.9144 2.9464)
			(stroke
				(width 0.1)
				(type default)
			)
			(layer "B.Fab")
		)
		(fp_line
			(start -0.9144 2.9464)
			(end -0.9144 0.1016)
			(stroke
				(width 0.1)
				(type default)
			)
			(layer "B.Fab")
		)
		(fp_circle
			(center -1.128776 -0.907288)
			(end -1.128776 -0.780288)
			(stroke
				(width 0.254)
				(type default)
			)
			(fill no)
			(layer "B.Fab")
		)
		(pad "1" smd rect
			(at 0 0)
			(size 1.524 0.762)
			(layers "B.Cu" "B.Mask" "B.Paste")
			(net "FM_DB_UART_SEL4_N")
		)
		(pad "2" smd rect
			(at 0 3.048 180)
			(size 1.524 0.762)
			(layers "B.Cu" "B.Mask" "B.Paste")
			(net "FM_DB_UART_SEL3_N")
		)
	)
	(footprint ""
		(layer "B.Cu")
		(at 18.5674 -84.3026 90)
		(property "Reference" "R9P7"
			(at 0 0 90)
			(layer "B.SilkS")
			(hide yes)
			(effects
				(font
					(size 1.27 1.27)
				)
				(justify mirror)
			)
		)
		(property "Value" ""
			(at 0 0 90)
			(layer "B.Fab")
			(effects
				(font
					(size 1.27 1.27)
				)
				(justify mirror)
			)
		)
		(duplicate_pad_numbers_are_jumpers no)
		(fp_poly
			(pts
				(xy 0.2794 -0.1016) (xy -0.2794 -0.1016) (xy -0.2794 0.9906) (xy 0.2794 0.9906)
			)
			(stroke
				(width 0)
				(type default)
			)
			(fill no)
			(layer "B.CrtYd")
		)
		(fp_line
			(start 0.2794 -0.1016)
			(end 0.2794 0.9906)
			(stroke
				(width 0.1)
				(type default)
			)
			(layer "B.Fab")
		)
		(fp_line
			(start -0.2794 -0.1016)
			(end 0.2794 -0.1016)
			(stroke
				(width 0.1)
				(type default)
			)
			(layer "B.Fab")
		)
		(fp_line
			(start 0.2794 0.9906)
			(end -0.2794 0.9906)
			(stroke
				(width 0.1)
				(type default)
			)
			(layer "B.Fab")
		)
		(fp_line
			(start -0.2794 0.9906)
			(end -0.2794 -0.1016)
			(stroke
				(width 0.1)
				(type default)
			)
			(layer "B.Fab")
		)
		(pad "1" smd rect
			(at 0 0 270)
			(size 0.508 0.508)
			(layers "B.Cu" "B.Mask" "B.Paste")
			(net "P12V_STBY")
		)
		(pad "2" smd rect
			(at 0 0.889 270)
			(size 0.508 0.508)
			(layers "B.Cu" "B.Mask" "B.Paste")
			(net "A_P12V_STBY_ADR_TRIGGER")
		)
		(zone
			(layer "B.Cu")
			(hatch none 0.5)
			(connect_pads
				(clearance 0)
			)
			(min_thickness 0.25)
			(keepout
				(tracks allowed)
				(vias not_allowed)
				(pads allowed)
				(copperpour not_allowed)
				(footprints allowed)
			)
			(placement
				(enabled no)
				(sheetname "")
			)
			(fill
				(thermal_gap 0.5)
				(thermal_bridge_width 0.5)
				(island_removal_mode 0)
			)
			(polygon
				(pts
					(xy 18.8214 -84.5566) (xy 18.8214 -84.0486) (xy 19.2024 -84.0486) (xy 19.2024 -84.5566)
				)
			)
		)
		(zone
			(layer "B.Cu")
			(hatch none 0.5)
			(connect_pads
				(clearance 0)
			)
			(min_thickness 0.25)
			(keepout
				(tracks not_allowed)
				(vias allowed)
				(pads allowed)
				(copperpour not_allowed)
				(footprints allowed)
			)
			(placement
				(enabled no)
				(sheetname "")
			)
			(fill
				(thermal_gap 0.5)
				(thermal_bridge_width 0.5)
				(island_removal_mode 0)
			)
			(polygon
				(pts
					(xy 19.2024 -84.5566) (xy 19.2024 -84.0486) (xy 18.8214 -84.0486) (xy 18.8214 -84.5566)
				)
			)
		)
	)
	(footprint ""
		(layer "B.Cu")
		(at 325.5264 -122.81916)
		(property "Reference" "U7E1"
			(at 0.64262 2.90957 0)
			(unlocked yes)
			(layer "B.SilkS")
			(effects
				(font
					(size 0.7874 0.5842)
					(thickness 0.1524)
				)
				(justify mirror)
			)
		)
		(property "Value" ""
			(at 0 0 0)
			(layer "B.Fab")
			(effects
				(font
					(size 1.27 1.27)
				)
				(justify mirror)
			)
		)
		(duplicate_pad_numbers_are_jumpers no)
		(fp_line
			(start -3.225292 -0.57404)
			(end -1.352804 -0.57404)
			(stroke
				(width 0.1524)
				(type default)
			)
			(layer "B.SilkS")
		)
		(fp_line
			(start -3.225038 2.52476)
			(end -1.348486 2.52476)
			(stroke
				(width 0.1524)
				(type default)
			)
			(layer "B.SilkS")
		)
		(fp_circle
			(center 1.454404 -0.556514)
			(end 1.581404 -0.556514)
			(stroke
				(width 0.254)
				(type default)
			)
			(fill no)
			(layer "B.SilkS")
		)
		(fp_poly
			(pts
				(xy -0.7366 -0.57404) (xy -3.8354 -0.57404) (xy -3.8354 2.52476) (xy -0.7366 2.52476)
			)
			(stroke
				(width 0)
				(type default)
			)
			(fill no)
			(layer "B.CrtYd")
		)
		(fp_line
			(start -3.8354 -0.57404)
			(end -3.8354 2.52476)
			(stroke
				(width 0.1)
				(type default)
			)
			(layer "B.Fab")
		)
		(fp_line
			(start -3.8354 2.52476)
			(end -0.7366 2.52476)
			(stroke
				(width 0.1)
				(type default)
			)
			(layer "B.Fab")
		)
		(fp_line
			(start -0.7366 -0.57404)
			(end -3.8354 -0.57404)
			(stroke
				(width 0.1)
				(type default)
			)
			(layer "B.Fab")
		)
		(fp_line
			(start -0.7366 2.52476)
			(end -0.7366 -0.57404)
			(stroke
				(width 0.1)
				(type default)
			)
			(layer "B.Fab")
		)
		(fp_circle
			(center 1.454404 -0.556514)
			(end 1.581404 -0.556514)
			(stroke
				(width 0.254)
				(type default)
			)
			(fill no)
			(layer "B.Fab")
		)
		(pad "1" smd rect
			(at 0 0 180)
			(size 1.778 0.4572)
			(layers "B.Cu" "B.Mask" "B.Paste")
			(net "PVCCIO_CPU0")
		)
		(pad "2" smd rect
			(at 0 0.65024 180)
			(size 1.778 0.4572)
			(layers "B.Cu" "B.Mask" "B.Paste")
			(net "SMB_DDR_DEF_SCL_G")
		)
		(pad "3" smd rect
			(at 0 1.30048 180)
			(size 1.778 0.4572)
			(layers "B.Cu" "B.Mask" "B.Paste")
			(net "SMB_DDR_DEF_SDA_G")
		)
		(pad "4" smd rect
			(at 0 1.95072 180)
			(size 1.778 0.4572)
			(layers "B.Cu" "B.Mask" "B.Paste")
			(net "GND")
		)
		(pad "5" smd rect
			(at -4.572 1.95072 180)
			(size 1.778 0.4572)
			(layers "B.Cu" "B.Mask" "B.Paste")
			(net "TP_SMB_DDR_DEF_EN")
		)
		(pad "6" smd rect
			(at -4.572 1.30048 180)
			(size 1.778 0.4572)
			(layers "B.Cu" "B.Mask" "B.Paste")
			(net "SMB_DDR_DEF_VPP_SDA_R")
		)
		(pad "7" smd rect
			(at -4.572 0.65024 180)
			(size 1.778 0.4572)
			(layers "B.Cu" "B.Mask" "B.Paste")
			(net "SMB_DDR_DEF_VPP_SCL_R")
		)
		(pad "8" smd rect
			(at -4.572 0 180)
			(size 1.778 0.4572)
			(layers "B.Cu" "B.Mask" "B.Paste")
			(net "PVPP_DEF")
		)
	)
)
